# BASEBOARD_FAB2 (Tioga Pass) — schematic netlist excerpt (pin names and nets, part order shuffled) for the footprints in the layout excerpt that follows; sources: Cadence DE-HDL packaged netlist, KiCad conversion of Wiwynn_Tioga_Pass_MB.brd

R1G25  RES  68.1K 1% EMPTY  pkg 0402  page 224 : A = VR_PVDDQ_GHJ_PH2_OCSET ; B = GND
C8F19  CAP  15.0PF 50V 5% COG  pkg 0402LF  page 101 : A = XTAL_CK_MNG_OUT ; B = GND
R7F8  RES  0 5.0% CHIP  pkg 0603  page 231 : A = VR_PVPP_ABC_BOOT ; B = VR_PVPP_ABC_BOOT_R

(kicad_pcb
	(version 20260206)
	(generator "pcbnew")
	(generator_version "10.0")
	(general
		(thickness 1.6)
		(legacy_teardrops no)
	)
	(paper "A4")
	(title_block
		(title "Wiwynn_Tioga_Pass_MB.brd")
		(comment 1 "Tioga Pass / footprints 1425-1427 of 4770")
	)
	(layers
		(0 "F.Cu" signal "TOP")
		(4 "In1.Cu" signal "L2GND")
		(6 "In2.Cu" signal "L3")
		(8 "In3.Cu" signal "L4GND")
		(10 "In4.Cu" signal "L5")
		(12 "In5.Cu" signal "L6GND")
		(14 "In6.Cu" signal "L7VCC")
		(16 "In7.Cu" signal "L8VCC")
		(18 "In8.Cu" signal "L9GND")
		(20 "In9.Cu" signal "L10")
		(22 "In10.Cu" signal "L11GND")
		(24 "In11.Cu" signal "L12")
		(26 "In12.Cu" signal "L13GND")
		(2 "B.Cu" signal "BOTTOM")
		(9 "F.Adhes" user "F.Adhesive")
		(11 "B.Adhes" user "B.Adhesive")
		(13 "F.Paste" user "Package Geometry/Pastemask Top")
		(15 "B.Paste" user "Package Geometry/Pastemask Bottom")
		(5 "F.SilkS" user "Ref Des/Silkscreen Top")
		(7 "B.SilkS" user "Ref Des/Silkscreen Bottom")
		(1 "F.Mask" user "Board Geometry/Soldermask Top")
		(3 "B.Mask" user "Board Geometry/Soldermask Bottom")
		(17 "Dwgs.User" user "User.Drawings")
		(19 "Cmts.User" user "User.Comments")
		(21 "Eco1.User" user "User.Eco1")
		(23 "Eco2.User" user "User.Eco2")
		(25 "Edge.Cuts" user "Board Geometry/Outline")
		(27 "Margin" user)
		(31 "F.CrtYd" user "Package Geometry/Place Bound Top")
		(29 "B.CrtYd" user "Package Geometry/Place Bound Bottom")
		(35 "F.Fab" user "Ref Des/Assembly Top")
		(33 "B.Fab" user "Ref Des/Assembly Bottom")
	)
	(footprint ""
		(layer "F.Cu")
		(at 482.00056 -34.6964 180)
		(property "Reference" "C8F19"
			(at -0.8382 -0.67818 180)
			(unlocked yes)
			(layer "F.SilkS")
			(effects
				(font
					(size 0.4064 0.254)
					(thickness 0.1524)
				)
				(justify left)
			)
		)
		(property "Value" ""
			(at 0 0 180)
			(layer "F.Fab")
			(effects
				(font
					(size 1.27 1.27)
				)
			)
		)
		(duplicate_pad_numbers_are_jumpers no)
		(fp_poly
			(pts
				(xy 0.3048 -0.1016) (xy 0.3048 0.9906) (xy -0.3048 0.9906) (xy -0.3048 -0.1016)
			)
			(stroke
				(width 0)
				(type default)
			)
			(fill no)
			(layer "F.CrtYd")
		)
		(fp_line
			(start 0.3048 0.9906)
			(end 0.3048 -0.1016)
			(stroke
				(width 0.1)
				(type default)
			)
			(layer "F.Fab")
		)
		(fp_line
			(start 0.3048 -0.1016)
			(end -0.3048 -0.1016)
			(stroke
				(width 0.1)
				(type default)
			)
			(layer "F.Fab")
		)
		(fp_line
			(start -0.3048 0.9906)
			(end 0.3048 0.9906)
			(stroke
				(width 0.1)
				(type default)
			)
			(layer "F.Fab")
		)
		(fp_line
			(start -0.3048 -0.1016)
			(end -0.3048 0.9906)
			(stroke
				(width 0.1)
				(type default)
			)
			(layer "F.Fab")
		)
		(pad "1" smd rect
			(at 0 0 180)
			(size 0.508 0.508)
			(layers "F.Cu" "F.Mask" "F.Paste")
			(net "XTAL_CK_MNG_OUT")
		)
		(pad "2" smd rect
			(at 0 0.889 180)
			(size 0.508 0.508)
			(layers "F.Cu" "F.Mask" "F.Paste")
			(net "GND")
		)
		(zone
			(layer "F.Cu")
			(hatch none 0.5)
			(connect_pads
				(clearance 0)
			)
			(min_thickness 0.25)
			(keepout
				(tracks not_allowed)
				(vias allowed)
				(pads allowed)
				(copperpour not_allowed)
				(footprints allowed)
			)
			(placement
				(enabled no)
				(sheetname "")
			)
			(fill
				(thermal_gap 0.5)
				(thermal_bridge_width 0.5)
				(island_removal_mode 0)
			)
			(polygon
				(pts
					(xy 482.25456 -35.3314) (xy 481.74656 -35.3314) (xy 481.74656 -34.9504) (xy 482.25456 -34.9504)
				)
			)
		)
		(zone
			(layer "F.Cu")
			(hatch none 0.5)
			(connect_pads
				(clearance 0)
			)
			(min_thickness 0.25)
			(keepout
				(tracks allowed)
				(vias not_allowed)
				(pads allowed)
				(copperpour not_allowed)
				(footprints allowed)
			)
			(placement
				(enabled no)
				(sheetname "")
			)
			(fill
				(thermal_gap 0.5)
				(thermal_bridge_width 0.5)
				(island_removal_mode 0)
			)
			(polygon
				(pts
					(xy 482.25456 -34.9504) (xy 481.74656 -34.9504) (xy 481.74656 -35.3314) (xy 482.25456 -35.3314)
				)
			)
		)
	)
	(footprint ""
		(layer "F.Cu")
		(at 340.775036 -26.973276)
		(property "Reference" "R7F8"
			(at 1.01473 0.656336 270)
			(unlocked yes)
			(layer "F.SilkS")
			(effects
				(font
					(size 0.4064 0.254)
					(thickness 0.1524)
				)
			)
		)
		(property "Value" ""
			(at 0 0 0)
			(layer "F.Fab")
			(effects
				(font
					(size 1.27 1.27)
				)
			)
		)
		(duplicate_pad_numbers_are_jumpers no)
		(fp_poly
			(pts
				(xy -0.4953 -0.2032) (xy 0.4953 -0.2032) (xy 0.4953 1.6002) (xy -0.4953 1.6002)
			)
			(stroke
				(width 0)
				(type default)
			)
			(fill no)
			(layer "F.CrtYd")
		)
		(fp_line
			(start -0.4953 -0.2032)
			(end 0.4953 -0.2032)
			(stroke
				(width 0.1)
				(type default)
			)
			(layer "F.Fab")
		)
		(fp_line
			(start -0.4953 1.6002)
			(end -0.4953 -0.2032)
			(stroke
				(width 0.1)
				(type default)
			)
			(layer "F.Fab")
		)
		(fp_line
			(start 0.4953 -0.2032)
			(end 0.4953 1.6002)
			(stroke
				(width 0.1)
				(type default)
			)
			(layer "F.Fab")
		)
		(fp_line
			(start 0.4953 1.6002)
			(end -0.4953 1.6002)
			(stroke
				(width 0.1)
				(type default)
			)
			(layer "F.Fab")
		)
		(pad "1" smd rect
			(at 0 0)
			(size 0.762 0.889)
			(layers "F.Cu" "F.Mask" "F.Paste")
			(net "VR_PVPP_ABC_BOOT")
		)
		(pad "2" smd rect
			(at 0 1.397)
			(size 0.762 0.889)
			(layers "F.Cu" "F.Mask" "F.Paste")
			(net "VR_PVPP_ABC_BOOT_R")
		)
		(zone
			(layer "F.Cu")
			(hatch none 0.5)
			(connect_pads
				(clearance 0)
			)
			(min_thickness 0.25)
			(keepout
				(tracks not_allowed)
				(vias allowed)
				(pads allowed)
				(copperpour not_allowed)
				(footprints allowed)
			)
			(placement
				(enabled no)
				(sheetname "")
			)
			(fill
				(thermal_gap 0.5)
				(thermal_bridge_width 0.5)
				(island_removal_mode 0)
			)
			(polygon
				(pts
					(xy 340.394036 -26.020776) (xy 341.156036 -26.020776) (xy 341.156036 -26.528776) (xy 340.394036 -26.528776)
				)
			)
		)
		(zone
			(layer "F.Cu")
			(hatch none 0.5)
			(connect_pads
				(clearance 0)
			)
			(min_thickness 0.25)
			(keepout
				(tracks allowed)
				(vias not_allowed)
				(pads allowed)
				(copperpour not_allowed)
				(footprints allowed)
			)
			(placement
				(enabled no)
				(sheetname "")
			)
			(fill
				(thermal_gap 0.5)
				(thermal_bridge_width 0.5)
				(island_removal_mode 0)
			)
			(polygon
				(pts
					(xy 341.156036 -26.020776) (xy 341.156036 -26.528776) (xy 340.394036 -26.528776) (xy 340.394036 -26.020776)
				)
			)
		)
	)
	(footprint ""
		(layer "F.Cu")
		(at -0.27432 -15.3924)
		(property "Reference" "R1G25"
			(at -0.8382 -0.67818 0)
			(unlocked yes)
			(layer "F.SilkS")
			(effects
				(font
					(size 0.4064 0.254)
					(thickness 0.1524)
				)
				(justify left)
			)
		)
		(property "Value" ""
			(at 0 0 0)
			(layer "F.Fab")
			(effects
				(font
					(size 1.27 1.27)
				)
			)
		)
		(duplicate_pad_numbers_are_jumpers no)
		(fp_rect
			(start -0.2794 0.9906)
			(end 0.2794 -0.1016)
			(stroke
				(width 0)
				(type default)
			)
			(fill no)
			(layer "F.CrtYd")
		)
		(fp_line
			(start -0.2794 -0.1016)
			(end -0.2794 0.9906)
			(stroke
				(width 0.1)
				(type default)
			)
			(layer "F.Fab")
		)
		(fp_line
			(start -0.2794 0.9906)
			(end 0.2794 0.9906)
			(stroke
				(width 0.1)
				(type default)
			)
			(layer "F.Fab")
		)
		(fp_line
			(start 0.2794 -0.1016)
			(end -0.2794 -0.1016)
			(stroke
				(width 0.1)
				(type default)
			)
			(layer "F.Fab")
		)
		(fp_line
			(start 0.2794 0.9906)
			(end 0.2794 -0.1016)
			(stroke
				(width 0.1)
				(type default)
			)
			(layer "F.Fab")
		)
		(pad "1" smd rect
			(at 0 0)
			(size 0.508 0.508)
			(layers "F.Cu" "F.Mask" "F.Paste")
			(net "VR_PVDDQ_GHJ_PH2_OCSET")
		)
		(pad "2" smd rect
			(at 0 0.889)
			(size 0.508 0.508)
			(layers "F.Cu" "F.Mask" "F.Paste")
			(net "GND")
		)
		(zone
			(layer "F.Cu")
			(hatch none 0.5)
			(connect_pads
				(clearance 0)
			)
			(min_thickness 0.25)
			(keepout
				(tracks not_allowed)
				(vias allowed)
				(pads allowed)
				(copperpour not_allowed)
				(footprints allowed)
			)
			(placement
				(enabled no)
				(sheetname "")
			)
			(fill
				(thermal_gap 0.5)
				(thermal_bridge_width 0.5)
				(island_removal_mode 0)
			)
			(polygon
				(pts
					(xy -0.52832 -14.7574) (xy -0.02032 -14.7574) (xy -0.02032 -15.1384) (xy -0.52832 -15.1384)
				)
			)
		)
		(zone
			(layer "F.Cu")
			(hatch none 0.5)
			(connect_pads
				(clearance 0)
			)
			(min_thickness 0.25)
			(keepout
				(tracks allowed)
				(vias not_allowed)
				(pads allowed)
				(copperpour not_allowed)
				(footprints allowed)
			)
			(placement
				(enabled no)
				(sheetname "")
			)
			(fill
				(thermal_gap 0.5)
				(thermal_bridge_width 0.5)
				(island_removal_mode 0)
			)
			(polygon
				(pts
					(xy -0.52832 -14.7574) (xy -0.02032 -14.7574) (xy -0.02032 -15.1384) (xy -0.52832 -15.1384)
				)
			)
		)
	)
)
